FILE_TYPE = MACRO_DRAWING;
SET COLOR_WIRE YELLOW;
SET COLOR_PROP ORANGE;
SET COLOR_DOT WHITE;
SET COLOR_ARC YELLOW;
SET COLOR_BODY GREEN;
SET COLOR_NOTE PURPLE;
SET PROP_DISPLAY VALUE;
SET PAGE_NUMBER P155;
FORCEADD QUANTA_TITLE_BLOCK_C..1
(-100 100);
FORCEPROP 1 LAST CUSTOM_TXT_CDS <NAME_2>
J 0
(-3275 150);
FORCEPROP 1 LAST CUSTOM_TXT_CDS <NAME_1>
J 0
(-3275 275);
FORCEPROP 1 LAST CUSTOM_TXT_CDS <Q_NUMBER>
J 0
(-1503 203);
DISPLAY 1.212766 (-1503 203);
FORCEPROP 1 LAST CUSTOM_TXT_CDS <Q_PROJ>
J 0
(-2482 202);
DISPLAY 1.212766 (-2482 202);
FORCEPROP 1 LAST CUSTOM_TXT_CDS <Q_REV>
J 0
(-284 203);
DISPLAY 1.212766 (-284 203);
FORCEPROP 1 LAST CUSTOM_TXT_CDS <CON_LAST_MODIFIED>
J 0
(-1985 115);
DISPLAY 0.978723 (-1985 115);
FORCEPROP 1 LAST CUSTOM_TXT_CDS <CON_PAGE_NUM> OF <CON_TOTAL_PAGES>
J 0
(-546 118);
DISPLAY 0.978723 (-546 118);
FORCEPROP 1 LAST Q_DEPT BU9
J 1
(-3863 149);
DISPLAY 1.957447 (-3863 149);
PAINT GREEN (-3863 149);
FORCEPROP 1 LAST Q_TITLE FAN - DUAL ROTOR (2/2)
J 0
(-9466 126);
DISPLAY 2.446809 (-9466 126);
PAINT GREEN (-9466 126);
FORCEPROP 2 LAST PAGE_BORDER TRUE
J 0
(-7990 5350);
DISPLAY 0.638298 (-7990 5350);
PAINT PINK (-7990 5350);
DISPLAY INVISIBLE (-7990 5350);
FORCEPROP 1 LAST CDS_LMAN_SYM_OUTLINE -9475,6775,100,-125
J 0
(-100 100);
DISPLAY 0.468085 (-100 100);
PAINT GREEN (-100 100);
DISPLAY INVISIBLE (-100 100);
FORCEPROP 2 LAST CDS_LIB pure_quanta
J 0
(-100 100);
DISPLAY INVISIBLE (-100 100);
FORCEPROP 1 LAST COMMENT_BODY TRUE
J 0
(-88 87);
DISPLAY 0.978723 (-88 87);
PAINT GREEN (-88 87);
DISPLAY INVISIBLE (-88 87);
FORCEPROP 2 LAST CDS_XR_PAGE_TITLE CR-155 : @T6G_MB_LIB.T6G(SCH_1):PAGE155
J 0
(-7990 5350);
DISPLAY 0.638298 (-7990 5350);
PAINT PINK (-7990 5350);
DISPLAY INVISIBLE (-7990 5350);
FORCEPROP 2 LAST CUSTOM_TXT_CDS <XR_PAGE_TITLE>
J 0
(-7990 5350);
DISPLAY 0.638298 (-7990 5350);
PAINT PINK (-7990 5350);
DISPLAY INVISIBLE (-7990 5350);
FORCEPROP 0 LAST CDS_CON_LAST_MODIFIED Wed Mar 09 20:27:32 2022
J 0
(-1985 115);
DISPLAY INVISIBLE (-1985 115);
QUIT
